(kicad_pcb
	(version 20260206)
	(generator "pcbnew")
	(generator_version "10.0")
	(general
		(thickness 1.6)
		(legacy_teardrops no)
	)
	(paper "A4")
	(title_block
		(title "pdpb — Lightning_PDPB_BRD.brd")
		(comment 1 "Lightning (Wiwynn / Facebook NVMe JBOF) / footprints 66-69 of 1140")
	)
	(layers
		(0 "F.Cu" signal "TOP")
		(4 "In1.Cu" signal "L2GND")
		(6 "In2.Cu" signal "L3")
		(8 "In3.Cu" signal "L4VCC")
		(10 "In4.Cu" signal "L5VCC")
		(12 "In5.Cu" signal "L6")
		(14 "In6.Cu" signal "L7GND")
		(2 "B.Cu" signal "BOTTOM")
		(9 "F.Adhes" user "F.Adhesive")
		(11 "B.Adhes" user "B.Adhesive")
		(13 "F.Paste" user "Package Geometry/Pastemask Top")
		(15 "B.Paste" user "Package Geometry/Pastemask Bottom")
		(5 "F.SilkS" user "Ref Des/Silkscreen Top")
		(7 "B.SilkS" user "Ref Des/Silkscreen Bottom")
		(1 "F.Mask" user "Board Geometry/Soldermask Top")
		(3 "B.Mask" user "Board Geometry/Soldermask Bottom")
		(17 "Dwgs.User" user "User.Drawings")
		(19 "Cmts.User" user "User.Comments")
		(21 "Eco1.User" user "User.Eco1")
		(23 "Eco2.User" user "User.Eco2")
		(25 "Edge.Cuts" user "Board Geometry/Outline")
		(27 "Margin" user)
		(31 "F.CrtYd" user "Package Geometry/Place Bound Top")
		(29 "B.CrtYd" user "Package Geometry/Place Bound Bottom")
		(35 "F.Fab" user "Ref Des/Assembly Top")
		(33 "B.Fab" user "Ref Des/Assembly Bottom")
	)
	(footprint ""
		(layer "F.Cu")
		(at 16.129 -370.332)
		(property "Reference" "Q83"
			(at 0 0 0)
			(layer "F.SilkS")
			(hide yes)
			(effects
				(font
					(size 1.27 1.27)
				)
			)
		)
		(property "Value" "2N7002A-7-GP"
			(at 0.127 -8.9662 0)
			(unlocked yes)
			(layer "F.Fab")
			(hide yes)
			(effects
				(font
					(size 1.016 1.016)
					(thickness 0.1524)
				)
			)
		)
		(property "Device Type" "SOT23DGS2D4H48"
			(at 0.127 -10.4902 0)
			(unlocked yes)
			(layer "F.Fab")
			(hide yes)
			(effects
				(font
					(size 1.016 1.016)
					(thickness 0.1524)
				)
			)
		)
		(duplicate_pad_numbers_are_jumpers no)
		(fp_line
			(start -1.651 -1.778)
			(end -1.651 1.778)
			(stroke
				(width 0.1524)
				(type default)
			)
			(layer "F.SilkS")
		)
		(fp_line
			(start -1.651 1.778)
			(end 1.651 1.778)
			(stroke
				(width 0.1524)
				(type default)
			)
			(layer "F.SilkS")
		)
		(fp_line
			(start 1.651 -1.778)
			(end -1.651 -1.778)
			(stroke
				(width 0.1524)
				(type default)
			)
			(layer "F.SilkS")
		)
		(fp_line
			(start 1.651 1.778)
			(end 1.651 -1.778)
			(stroke
				(width 0.1524)
				(type default)
			)
			(layer "F.SilkS")
		)
		(fp_poly
			(pts
				(xy -1.778 1.8796) (xy -1.778 -1.8796) (xy 1.778 -1.8796) (xy 1.778 1.8796)
			)
			(stroke
				(width 0)
				(type default)
			)
			(fill no)
			(layer "F.CrtYd")
		)
		(fp_poly
			(pts
				(xy -1.778 1.8796) (xy -1.778 -1.8796) (xy 1.778 -1.8796) (xy 1.778 1.8796)
			)
			(stroke
				(width 0)
				(type default)
			)
			(fill no)
			(layer "F.Fab")
		)
		(pad "D" smd custom
			(at 0 -0.9525)
			(size 0.1905 0.1905)
			(layers "F.Cu" "F.Mask" "F.Paste")
			(net "SSD_ACT_DR11_MOS_N")
			(options
				(clearance outline)
				(anchor circle)
			)
			(primitives
				(gr_poly
					(pts
						(arc
							(start -0.1778 0.5715)
							(mid -0.321484 0.511984)
							(end -0.381 0.3683)
						)
						(arc
							(start -0.381 -0.3683)
							(mid -0.321484 -0.511984)
							(end -0.1778 -0.5715)
						)
						(arc
							(start 0.1778 -0.5715)
							(mid 0.321484 -0.511984)
							(end 0.381 -0.3683)
						)
						(arc
							(start 0.381 0.3683)
							(mid 0.321484 0.511984)
							(end 0.1778 0.5715)
						)
					)
					(width 0)
					(fill yes)
				)
			)
		)
		(pad "G" smd custom
			(at -0.98425 0.9525)
			(size 0.1905 0.1905)
			(layers "F.Cu" "F.Mask" "F.Paste")
			(net "ATTN_LED_DR11_AND_R")
			(options
				(clearance outline)
				(anchor circle)
			)
			(primitives
				(gr_poly
					(pts
						(arc
							(start -0.1778 0.5715)
							(mid -0.321484 0.511984)
							(end -0.381 0.3683)
						)
						(arc
							(start -0.381 -0.3683)
							(mid -0.321484 -0.511984)
							(end -0.1778 -0.5715)
						)
						(arc
							(start 0.1778 -0.5715)
							(mid 0.321484 -0.511984)
							(end 0.381 -0.3683)
						)
						(arc
							(start 0.381 0.3683)
							(mid 0.321484 0.511984)
							(end 0.1778 0.5715)
						)
					)
					(width 0)
					(fill yes)
				)
			)
		)
		(pad "S" smd custom
			(at 0.98425 0.9525)
			(size 0.1905 0.1905)
			(layers "F.Cu" "F.Mask" "F.Paste")
			(net "SSD_ACT_DR11_R")
			(options
				(clearance outline)
				(anchor circle)
			)
			(primitives
				(gr_poly
					(pts
						(arc
							(start -0.1778 0.5715)
							(mid -0.321484 0.511984)
							(end -0.381 0.3683)
						)
						(arc
							(start -0.381 -0.3683)
							(mid -0.321484 -0.511984)
							(end -0.1778 -0.5715)
						)
						(arc
							(start 0.1778 -0.5715)
							(mid 0.321484 -0.511984)
							(end 0.381 -0.3683)
						)
						(arc
							(start 0.381 0.3683)
							(mid 0.321484 0.511984)
							(end 0.1778 0.5715)
						)
					)
					(width 0)
					(fill yes)
				)
			)
		)
	)
	(footprint ""
		(layer "F.Cu")
		(at 229.67696 -344.118692)
		(property "Reference" "C9519"
			(at 0 0 0)
			(layer "F.SilkS")
			(hide yes)
			(effects
				(font
					(size 1.27 1.27)
				)
			)
		)
		(property "Value" "SCD1U16V2KX-3GP"
			(at 1.1811 -2.7051 0)
			(unlocked yes)
			(layer "F.Fab")
			(hide yes)
			(effects
				(font
					(size 1.016 1.016)
					(thickness 0.1524)
				)
			)
		)
		(property "Device Type" "C402H22"
			(at 1.1811 -4.2291 0)
			(unlocked yes)
			(layer "F.Fab")
			(hide yes)
			(effects
				(font
					(size 1.016 1.016)
					(thickness 0.1524)
				)
			)
		)
		(duplicate_pad_numbers_are_jumpers no)
		(fp_rect
			(start -0.4318 0.9525)
			(end 0.4318 -0.9525)
			(stroke
				(width 0)
				(type default)
			)
			(fill no)
			(layer "F.CrtYd")
		)
		(fp_rect
			(start -0.4318 0.9525)
			(end 0.4318 -0.9525)
			(stroke
				(width 0)
				(type default)
			)
			(fill no)
			(layer "F.Fab")
		)
		(pad "1" smd custom
			(at 0 -0.4445)
			(size 0.1524 0.1524)
			(layers "F.Cu" "F.Mask" "F.Paste")
			(net "P3V3")
			(options
				(clearance outline)
				(anchor circle)
			)
			(primitives
				(gr_poly
					(pts
						(arc
							(start 0.3048 -0.2032)
							(mid 0.275042 -0.275042)
							(end 0.2032 -0.3048)
						)
						(arc
							(start -0.2032 -0.3048)
							(mid -0.275042 -0.275042)
							(end -0.3048 -0.2032)
						)
						(arc
							(start -0.3048 0.2032)
							(mid -0.275042 0.275042)
							(end -0.2032 0.3048)
						)
						(arc
							(start 0.2032 0.3048)
							(mid 0.275042 0.275042)
							(end 0.3048 0.2032)
						)
					)
					(width 0)
					(fill yes)
				)
			)
		)
		(pad "2" smd custom
			(at 0 0.4445)
			(size 0.1524 0.1524)
			(layers "F.Cu" "F.Mask" "F.Paste")
			(net "GND")
			(options
				(clearance outline)
				(anchor circle)
			)
			(primitives
				(gr_poly
					(pts
						(arc
							(start 0.3048 -0.2032)
							(mid 0.275042 -0.275042)
							(end 0.2032 -0.3048)
						)
						(arc
							(start -0.2032 -0.3048)
							(mid -0.275042 -0.275042)
							(end -0.3048 -0.2032)
						)
						(arc
							(start -0.3048 0.2032)
							(mid -0.275042 0.275042)
							(end -0.2032 0.3048)
						)
						(arc
							(start 0.2032 0.3048)
							(mid 0.275042 0.275042)
							(end 0.3048 0.2032)
						)
					)
					(width 0)
					(fill yes)
				)
			)
		)
	)
	(footprint ""
		(layer "F.Cu")
		(at 37.7698 -311.8104)
		(property "Reference" "Q19"
			(at 0 0 0)
			(layer "F.SilkS")
			(hide yes)
			(effects
				(font
					(size 1.27 1.27)
				)
			)
		)
		(property "Value" "2N7002A-7-GP"
			(at 0.127 -8.9662 0)
			(unlocked yes)
			(layer "F.Fab")
			(hide yes)
			(effects
				(font
					(size 1.016 1.016)
					(thickness 0.1524)
				)
			)
		)
		(property "Device Type" "SOT23DGS2D4H48"
			(at 0.127 -10.4902 0)
			(unlocked yes)
			(layer "F.Fab")
			(hide yes)
			(effects
				(font
					(size 1.016 1.016)
					(thickness 0.1524)
				)
			)
		)
		(duplicate_pad_numbers_are_jumpers no)
		(fp_line
			(start -1.651 -1.778)
			(end -1.651 1.778)
			(stroke
				(width 0.1524)
				(type default)
			)
			(layer "F.SilkS")
		)
		(fp_line
			(start -1.651 1.778)
			(end 1.651 1.778)
			(stroke
				(width 0.1524)
				(type default)
			)
			(layer "F.SilkS")
		)
		(fp_line
			(start 1.651 -1.778)
			(end -1.651 -1.778)
			(stroke
				(width 0.1524)
				(type default)
			)
			(layer "F.SilkS")
		)
		(fp_line
			(start 1.651 1.778)
			(end 1.651 -1.778)
			(stroke
				(width 0.1524)
				(type default)
			)
			(layer "F.SilkS")
		)
		(fp_poly
			(pts
				(xy -1.778 1.8796) (xy -1.778 -1.8796) (xy 1.778 -1.8796) (xy 1.778 1.8796)
			)
			(stroke
				(width 0)
				(type default)
			)
			(fill no)
			(layer "F.CrtYd")
		)
		(fp_poly
			(pts
				(xy -1.778 1.8796) (xy -1.778 -1.8796) (xy 1.778 -1.8796) (xy 1.778 1.8796)
			)
			(stroke
				(width 0)
				(type default)
			)
			(fill no)
			(layer "F.Fab")
		)
		(pad "D" smd custom
			(at 0 -0.9525)
			(size 0.1905 0.1905)
			(layers "F.Cu" "F.Mask" "F.Paste")
			(net "SW_SSD11_R")
			(options
				(clearance outline)
				(anchor circle)
			)
			(primitives
				(gr_poly
					(pts
						(arc
							(start -0.1778 0.5715)
							(mid -0.321484 0.511984)
							(end -0.381 0.3683)
						)
						(arc
							(start -0.381 -0.3683)
							(mid -0.321484 -0.511984)
							(end -0.1778 -0.5715)
						)
						(arc
							(start 0.1778 -0.5715)
							(mid 0.321484 -0.511984)
							(end 0.381 -0.3683)
						)
						(arc
							(start 0.381 0.3683)
							(mid 0.321484 0.511984)
							(end 0.1778 0.5715)
						)
					)
					(width 0)
					(fill yes)
				)
			)
		)
		(pad "G" smd custom
			(at -0.98425 0.9525)
			(size 0.1905 0.1905)
			(layers "F.Cu" "F.Mask" "F.Paste")
			(net "SSD11_PWREN")
			(options
				(clearance outline)
				(anchor circle)
			)
			(primitives
				(gr_poly
					(pts
						(arc
							(start -0.1778 0.5715)
							(mid -0.321484 0.511984)
							(end -0.381 0.3683)
						)
						(arc
							(start -0.381 -0.3683)
							(mid -0.321484 -0.511984)
							(end -0.1778 -0.5715)
						)
						(arc
							(start 0.1778 -0.5715)
							(mid 0.321484 -0.511984)
							(end 0.381 -0.3683)
						)
						(arc
							(start 0.381 0.3683)
							(mid 0.321484 0.511984)
							(end 0.1778 0.5715)
						)
					)
					(width 0)
					(fill yes)
				)
			)
		)
		(pad "S" smd custom
			(at 0.98425 0.9525)
			(size 0.1905 0.1905)
			(layers "F.Cu" "F.Mask" "F.Paste")
			(net "GND")
			(options
				(clearance outline)
				(anchor circle)
			)
			(primitives
				(gr_poly
					(pts
						(arc
							(start -0.1778 0.5715)
							(mid -0.321484 0.511984)
							(end -0.381 0.3683)
						)
						(arc
							(start -0.381 -0.3683)
							(mid -0.321484 -0.511984)
							(end -0.1778 -0.5715)
						)
						(arc
							(start 0.1778 -0.5715)
							(mid 0.321484 -0.511984)
							(end 0.381 -0.3683)
						)
						(arc
							(start 0.381 0.3683)
							(mid 0.321484 0.511984)
							(end 0.1778 0.5715)
						)
					)
					(width 0)
					(fill yes)
				)
			)
		)
	)
	(footprint ""
		(layer "F.Cu")
		(at 228.2952 -449.834 180)
		(property "Reference" "SR1122"
			(at 0 0 180)
			(layer "F.SilkS")
			(hide yes)
			(effects
				(font
					(size 1.27 1.27)
				)
			)
		)
		(property "Value" "4K7R2J-2-GP"
			(at 0.064008 -3.993896 180)
			(unlocked yes)
			(layer "F.Fab")
			(hide yes)
			(effects
				(font
					(size 1.016 1.016)
					(thickness 0.1524)
				)
			)
		)
		(property "Device Type" "R402H16"
			(at 0.064008 -5.517896 180)
			(unlocked yes)
			(layer "F.Fab")
			(hide yes)
			(effects
				(font
					(size 1.016 1.016)
					(thickness 0.1524)
				)
			)
		)
		(duplicate_pad_numbers_are_jumpers no)
		(fp_line
			(start 0.508 -0.9398)
			(end -0.508 -0.9398)
			(stroke
				(width 0.1524)
				(type default)
			)
			(layer "F.SilkS")
		)
		(fp_line
			(start -0.508 -0.9398)
			(end -0.508 0.9398)
			(stroke
				(width 0.1524)
				(type default)
			)
			(layer "F.SilkS")
		)
		(fp_rect
			(start -0.508 0.9398)
			(end 0.508 -0.9398)
			(stroke
				(width 0)
				(type default)
			)
			(fill no)
			(layer "F.CrtYd")
		)
		(fp_rect
			(start -0.508 0.9398)
			(end 0.508 -0.9398)
			(stroke
				(width 0)
				(type default)
			)
			(fill no)
			(layer "F.Fab")
		)
		(pad "1" smd custom
			(at 0 -0.4445 180)
			(size 0.1397 0.1397)
			(layers "F.Cu" "F.Mask" "F.Paste")
			(net "P3V3")
			(options
				(clearance outline)
				(anchor circle)
			)
			(primitives
				(gr_poly
					(pts
						(arc
							(start -0.1778 -0.2794)
							(mid -0.249642 -0.249642)
							(end -0.2794 -0.1778)
						)
						(arc
							(start -0.2794 0.1778)
							(mid -0.249642 0.249642)
							(end -0.1778 0.2794)
						)
						(arc
							(start 0.1778 0.2794)
							(mid 0.249642 0.249642)
							(end 0.2794 0.1778)
						)
						(arc
							(start 0.2794 -0.1778)
							(mid 0.249642 -0.249642)
							(end 0.1778 -0.2794)
						)
					)
					(width 0)
					(fill yes)
				)
			)
		)
		(pad "2" smd custom
			(at 0 0.4445 180)
			(size 0.1397 0.1397)
			(layers "F.Cu" "F.Mask" "F.Paste")
			(net "SSD_ACT_DR0")
			(options
				(clearance outline)
				(anchor circle)
			)
			(primitives
				(gr_poly
					(pts
						(arc
							(start -0.1778 -0.2794)
							(mid -0.249642 -0.249642)
							(end -0.2794 -0.1778)
						)
						(arc
							(start -0.2794 0.1778)
							(mid -0.249642 0.249642)
							(end -0.1778 0.2794)
						)
						(arc
							(start 0.1778 0.2794)
							(mid 0.249642 0.249642)
							(end 0.2794 0.1778)
						)
						(arc
							(start 0.2794 -0.1778)
							(mid 0.249642 -0.249642)
							(end 0.1778 -0.2794)
						)
					)
					(width 0)
					(fill yes)
				)
			)
		)
	)
)
